(kicad_pcb
	(version 20260206)
	(generator "pcbnew")
	(generator_version "10.0")
	(general
		(thickness 1.6)
		(legacy_teardrops no)
	)
	(paper "A4")
	(title_block
		(title "Bryce Canyon_IOM_IOC_16318-2_OCP.brd")
		(comment 1 "Bryce Canyon / footprints 171-178 of 1605")
	)
	(layers
		(0 "F.Cu" signal "TOP")
		(4 "In1.Cu" signal "L2GND")
		(6 "In2.Cu" signal "L3")
		(8 "In3.Cu" signal "L4VCC")
		(10 "In4.Cu" signal "L5VCC")
		(12 "In5.Cu" signal "L6")
		(14 "In6.Cu" signal "L7GND")
		(2 "B.Cu" signal "BOTTOM")
		(9 "F.Adhes" user "F.Adhesive")
		(11 "B.Adhes" user "B.Adhesive")
		(13 "F.Paste" user "Package Geometry/Pastemask Top")
		(15 "B.Paste" user "Package Geometry/Pastemask Bottom")
		(5 "F.SilkS" user "Ref Des/Silkscreen Top")
		(7 "B.SilkS" user "Ref Des/Silkscreen Bottom")
		(1 "F.Mask" user "Board Geometry/Soldermask Top")
		(3 "B.Mask" user "Board Geometry/Soldermask Bottom")
		(17 "Dwgs.User" user "User.Drawings")
		(19 "Cmts.User" user "User.Comments")
		(21 "Eco1.User" user "User.Eco1")
		(23 "Eco2.User" user "User.Eco2")
		(25 "Edge.Cuts" user "Board Geometry/Outline")
		(27 "Margin" user)
		(31 "F.CrtYd" user "Package Geometry/Place Bound Top")
		(29 "B.CrtYd" user "Package Geometry/Place Bound Bottom")
		(35 "F.Fab" user "Ref Des/Assembly Top")
		(33 "B.Fab" user "Ref Des/Assembly Bottom")
	)
	(footprint ""
		(layer "F.Cu")
		(at 92.342462 -121.402348 180)
		(property "Reference" "R797"
			(at 0 0 180)
			(layer "F.SilkS")
			(hide yes)
			(effects
				(font
					(size 1.27 1.27)
				)
			)
		)
		(property "Value" "0R2J-2-GP"
			(at 0.064008 -3.993896 180)
			(unlocked yes)
			(layer "F.Fab")
			(hide yes)
			(effects
				(font
					(size 1.016 1.016)
					(thickness 0.1524)
				)
			)
		)
		(property "Device Type" "R402H16"
			(at 0.064008 -5.517896 180)
			(unlocked yes)
			(layer "F.Fab")
			(hide yes)
			(effects
				(font
					(size 1.016 1.016)
					(thickness 0.1524)
				)
			)
		)
		(duplicate_pad_numbers_are_jumpers no)
		(fp_line
			(start 0.508 -0.9398)
			(end -0.508 -0.9398)
			(stroke
				(width 0.1524)
				(type default)
			)
			(layer "F.SilkS")
		)
		(fp_line
			(start -0.508 -0.9398)
			(end -0.508 0.9398)
			(stroke
				(width 0.1524)
				(type default)
			)
			(layer "F.SilkS")
		)
		(fp_rect
			(start -0.508 0.9398)
			(end 0.508 -0.9398)
			(stroke
				(width 0)
				(type default)
			)
			(fill no)
			(layer "F.CrtYd")
		)
		(fp_rect
			(start -0.508 0.9398)
			(end 0.508 -0.9398)
			(stroke
				(width 0)
				(type default)
			)
			(fill no)
			(layer "F.Fab")
		)
		(pad "1" smd custom
			(at 0 -0.4445 180)
			(size 0.1397 0.1397)
			(layers "F.Cu" "F.Mask" "F.Paste")
			(net "UART_BMC_COMP_IN_RX")
			(options
				(clearance outline)
				(anchor circle)
			)
			(primitives
				(gr_poly
					(pts
						(arc
							(start -0.1778 -0.2794)
							(mid -0.249642 -0.249642)
							(end -0.2794 -0.1778)
						)
						(arc
							(start -0.2794 0.1778)
							(mid -0.249642 0.249642)
							(end -0.1778 0.2794)
						)
						(arc
							(start 0.1778 0.2794)
							(mid 0.249642 0.249642)
							(end 0.2794 0.1778)
						)
						(arc
							(start 0.2794 -0.1778)
							(mid 0.249642 -0.249642)
							(end 0.1778 -0.2794)
						)
					)
					(width 0)
					(fill yes)
				)
			)
		)
		(pad "2" smd custom
			(at 0 0.4445 180)
			(size 0.1397 0.1397)
			(layers "F.Cu" "F.Mask" "F.Paste")
			(net "UART_BMC_COMP_IN_RX_R")
			(options
				(clearance outline)
				(anchor circle)
			)
			(primitives
				(gr_poly
					(pts
						(arc
							(start -0.1778 -0.2794)
							(mid -0.249642 -0.249642)
							(end -0.2794 -0.1778)
						)
						(arc
							(start -0.2794 0.1778)
							(mid -0.249642 0.249642)
							(end -0.1778 0.2794)
						)
						(arc
							(start 0.1778 0.2794)
							(mid 0.249642 0.249642)
							(end 0.2794 0.1778)
						)
						(arc
							(start 0.2794 -0.1778)
							(mid 0.249642 -0.249642)
							(end 0.1778 -0.2794)
						)
					)
					(width 0)
					(fill yes)
				)
			)
		)
	)
	(footprint ""
		(layer "F.Cu")
		(at 25.682702 -132.353558 180)
		(property "Reference" "R232"
			(at 0 0 180)
			(layer "F.SilkS")
			(hide yes)
			(effects
				(font
					(size 1.27 1.27)
				)
			)
		)
		(property "Value" "120R2F-GP"
			(at 0.064008 -3.993896 180)
			(unlocked yes)
			(layer "F.Fab")
			(hide yes)
			(effects
				(font
					(size 1.016 1.016)
					(thickness 0.1524)
				)
			)
		)
		(property "Device Type" "R402H16"
			(at 0.064008 -5.517896 180)
			(unlocked yes)
			(layer "F.Fab")
			(hide yes)
			(effects
				(font
					(size 1.016 1.016)
					(thickness 0.1524)
				)
			)
		)
		(duplicate_pad_numbers_are_jumpers no)
		(fp_line
			(start 0.508 -0.9398)
			(end -0.508 -0.9398)
			(stroke
				(width 0.1524)
				(type default)
			)
			(layer "F.SilkS")
		)
		(fp_line
			(start -0.508 -0.9398)
			(end -0.508 0.9398)
			(stroke
				(width 0.1524)
				(type default)
			)
			(layer "F.SilkS")
		)
		(fp_rect
			(start -0.508 0.9398)
			(end 0.508 -0.9398)
			(stroke
				(width 0)
				(type default)
			)
			(fill no)
			(layer "F.CrtYd")
		)
		(fp_rect
			(start -0.508 0.9398)
			(end 0.508 -0.9398)
			(stroke
				(width 0)
				(type default)
			)
			(fill no)
			(layer "F.Fab")
		)
		(pad "1" smd custom
			(at 0 -0.4445 180)
			(size 0.1397 0.1397)
			(layers "F.Cu" "F.Mask" "F.Paste")
			(net "MEMBA_1")
			(options
				(clearance outline)
				(anchor circle)
			)
			(primitives
				(gr_poly
					(pts
						(arc
							(start -0.1778 -0.2794)
							(mid -0.249642 -0.249642)
							(end -0.2794 -0.1778)
						)
						(arc
							(start -0.2794 0.1778)
							(mid -0.249642 0.249642)
							(end -0.1778 0.2794)
						)
						(arc
							(start 0.1778 0.2794)
							(mid 0.249642 0.249642)
							(end 0.2794 0.1778)
						)
						(arc
							(start 0.2794 -0.1778)
							(mid 0.249642 -0.249642)
							(end 0.1778 -0.2794)
						)
					)
					(width 0)
					(fill yes)
				)
			)
		)
		(pad "2" smd custom
			(at 0 0.4445 180)
			(size 0.1397 0.1397)
			(layers "F.Cu" "F.Mask" "F.Paste")
			(net "P1V2_STBY")
			(options
				(clearance outline)
				(anchor circle)
			)
			(primitives
				(gr_poly
					(pts
						(arc
							(start -0.1778 -0.2794)
							(mid -0.249642 -0.249642)
							(end -0.2794 -0.1778)
						)
						(arc
							(start -0.2794 0.1778)
							(mid -0.249642 0.249642)
							(end -0.1778 0.2794)
						)
						(arc
							(start 0.1778 0.2794)
							(mid 0.249642 0.249642)
							(end 0.2794 0.1778)
						)
						(arc
							(start 0.2794 -0.1778)
							(mid 0.249642 -0.249642)
							(end 0.1778 -0.2794)
						)
					)
					(width 0)
					(fill yes)
				)
			)
		)
	)
	(footprint ""
		(layer "F.Cu")
		(at 90.424 -26.8478 90)
		(property "Reference" "L23"
			(at 0 0 90)
			(layer "F.SilkS")
			(hide yes)
			(effects
				(font
					(size 1.27 1.27)
				)
			)
		)
		(property "Value" "BLM21PG300SN-2GP"
			(at 0.0254 -5.6896 90)
			(unlocked yes)
			(layer "F.Fab")
			(hide yes)
			(effects
				(font
					(size 1.016 1.016)
					(thickness 0.1524)
				)
			)
		)
		(property "Device Type" "L20125H42"
			(at 0.0254 -7.5946 90)
			(unlocked yes)
			(layer "F.Fab")
			(hide yes)
			(effects
				(font
					(size 1.016 1.016)
					(thickness 0.1524)
				)
			)
		)
		(duplicate_pad_numbers_are_jumpers no)
		(fp_line
			(start 0.9144 -1.7018)
			(end -0.9144 -1.7018)
			(stroke
				(width 0.1524)
				(type default)
			)
			(layer "F.SilkS")
		)
		(fp_line
			(start -0.9144 -1.7018)
			(end -0.9144 1.7018)
			(stroke
				(width 0.1524)
				(type default)
			)
			(layer "F.SilkS")
		)
		(fp_line
			(start 0.9144 1.7018)
			(end 0.9144 -1.7018)
			(stroke
				(width 0.1524)
				(type default)
			)
			(layer "F.SilkS")
		)
		(fp_line
			(start -0.9144 1.7018)
			(end 0.9144 1.7018)
			(stroke
				(width 0.1524)
				(type default)
			)
			(layer "F.SilkS")
		)
		(fp_rect
			(start -1.0033 1.778)
			(end 1.0033 -1.778)
			(stroke
				(width 0)
				(type default)
			)
			(fill no)
			(layer "F.CrtYd")
		)
		(fp_poly
			(pts
				(xy -1.0033 -1.778) (xy 1.0033 -1.778) (xy 1.0033 1.778) (xy -1.0033 1.778)
			)
			(stroke
				(width 0)
				(type default)
			)
			(fill no)
			(layer "F.Fab")
		)
		(pad "1" smd rect
			(at 0 -0.9652 90)
			(size 1.397 1.143)
			(layers "F.Cu" "F.Mask" "F.Paste")
			(net "P5V_VBUS_CONN")
		)
		(pad "2" smd rect
			(at 0 0.9652 90)
			(size 1.397 1.143)
			(layers "F.Cu" "F.Mask" "F.Paste")
			(net "P5V_USB")
		)
	)
	(footprint ""
		(layer "F.Cu")
		(at 31.70428 -186.992514 180)
		(property "Reference" "C173"
			(at 0 0 180)
			(layer "F.SilkS")
			(hide yes)
			(effects
				(font
					(size 1.27 1.27)
				)
			)
		)
		(property "Value" "SC10U16V5KX-7-GP-U"
			(at -0.0762 -6.1214 180)
			(unlocked yes)
			(layer "F.Fab")
			(hide yes)
			(effects
				(font
					(size 1.016 1.016)
					(thickness 0.1524)
				)
			)
		)
		(property "Device Type" "C805H58"
			(at -0.0762 -8.1534 180)
			(unlocked yes)
			(layer "F.Fab")
			(hide yes)
			(effects
				(font
					(size 1.016 1.016)
					(thickness 0.1524)
				)
			)
		)
		(duplicate_pad_numbers_are_jumpers no)
		(fp_line
			(start 0.635 0)
			(end -0.635 0)
			(stroke
				(width 0.508)
				(type default)
			)
			(layer "F.SilkS")
		)
		(fp_rect
			(start -0.9652 1.778)
			(end 0.9652 -1.778)
			(stroke
				(width 0)
				(type default)
			)
			(fill no)
			(layer "F.CrtYd")
		)
		(fp_poly
			(pts
				(xy -0.9652 -1.778) (xy 0.9652 -1.778) (xy 0.9652 1.778) (xy -0.9652 1.778)
			)
			(stroke
				(width 0)
				(type default)
			)
			(fill no)
			(layer "F.Fab")
		)
		(pad "1" smd rect
			(at 0 -0.9652 180)
			(size 1.397 1.143)
			(layers "F.Cu" "F.Mask" "F.Paste")
			(net "P12V_STBY_VIN_PU2")
		)
		(pad "2" smd rect
			(at 0 0.9652 180)
			(size 1.397 1.143)
			(layers "F.Cu" "F.Mask" "F.Paste")
			(net "GND")
		)
	)
	(footprint ""
		(layer "F.Cu")
		(at 45.432726 -131.748022 180)
		(property "Reference" "R264"
			(at 0 0 180)
			(layer "F.SilkS")
			(hide yes)
			(effects
				(font
					(size 1.27 1.27)
				)
			)
		)
		(property "Value" "4K7R2F-GP"
			(at 0.064008 -3.993896 180)
			(unlocked yes)
			(layer "F.Fab")
			(hide yes)
			(effects
				(font
					(size 1.016 1.016)
					(thickness 0.1524)
				)
			)
		)
		(property "Device Type" "R402H16"
			(at 0.064008 -5.517896 180)
			(unlocked yes)
			(layer "F.Fab")
			(hide yes)
			(effects
				(font
					(size 1.016 1.016)
					(thickness 0.1524)
				)
			)
		)
		(duplicate_pad_numbers_are_jumpers no)
		(fp_line
			(start 0.508 -0.9398)
			(end -0.508 -0.9398)
			(stroke
				(width 0.1524)
				(type default)
			)
			(layer "F.SilkS")
		)
		(fp_line
			(start -0.508 -0.9398)
			(end -0.508 0.9398)
			(stroke
				(width 0.1524)
				(type default)
			)
			(layer "F.SilkS")
		)
		(fp_rect
			(start -0.508 0.9398)
			(end 0.508 -0.9398)
			(stroke
				(width 0)
				(type default)
			)
			(fill no)
			(layer "F.CrtYd")
		)
		(fp_rect
			(start -0.508 0.9398)
			(end 0.508 -0.9398)
			(stroke
				(width 0)
				(type default)
			)
			(fill no)
			(layer "F.Fab")
		)
		(pad "1" smd custom
			(at 0 -0.4445 180)
			(size 0.1397 0.1397)
			(layers "F.Cu" "F.Mask" "F.Paste")
			(net "P3V3_STBY")
			(options
				(clearance outline)
				(anchor circle)
			)
			(primitives
				(gr_poly
					(pts
						(arc
							(start -0.1778 -0.2794)
							(mid -0.249642 -0.249642)
							(end -0.2794 -0.1778)
						)
						(arc
							(start -0.2794 0.1778)
							(mid -0.249642 0.249642)
							(end -0.1778 0.2794)
						)
						(arc
							(start 0.1778 0.2794)
							(mid 0.249642 0.249642)
							(end 0.2794 0.1778)
						)
						(arc
							(start 0.2794 -0.1778)
							(mid 0.249642 -0.249642)
							(end 0.1778 -0.2794)
						)
					)
					(width 0)
					(fill yes)
				)
			)
		)
		(pad "2" smd custom
			(at 0 0.4445 180)
			(size 0.1397 0.1397)
			(layers "F.Cu" "F.Mask" "F.Paste")
			(net "BMC_GPIOY2")
			(options
				(clearance outline)
				(anchor circle)
			)
			(primitives
				(gr_poly
					(pts
						(arc
							(start -0.1778 -0.2794)
							(mid -0.249642 -0.249642)
							(end -0.2794 -0.1778)
						)
						(arc
							(start -0.2794 0.1778)
							(mid -0.249642 0.249642)
							(end -0.1778 0.2794)
						)
						(arc
							(start 0.1778 0.2794)
							(mid 0.249642 0.249642)
							(end 0.2794 0.1778)
						)
						(arc
							(start 0.2794 -0.1778)
							(mid 0.249642 -0.249642)
							(end 0.1778 -0.2794)
						)
					)
					(width 0)
					(fill yes)
				)
			)
		)
	)
	(footprint ""
		(layer "F.Cu")
		(at 160.69564 -132.471922 -90)
		(property "Reference" "C207"
			(at 0 0 270)
			(layer "F.SilkS")
			(hide yes)
			(effects
				(font
					(size 1.27 1.27)
				)
			)
		)
		(property "Value" "SCD1U50V3KX-GP"
			(at 0 -2.8194 270)
			(unlocked yes)
			(layer "F.Fab")
			(hide yes)
			(effects
				(font
					(size 1.016 1.016)
					(thickness 0.1524)
				)
			)
		)
		(property "Device Type" "C603H36"
			(at 0 -4.3434 270)
			(unlocked yes)
			(layer "F.Fab")
			(hide yes)
			(effects
				(font
					(size 1.016 1.016)
					(thickness 0.1524)
				)
			)
		)
		(duplicate_pad_numbers_are_jumpers no)
		(fp_line
			(start 0.508 0)
			(end -0.508 0)
			(stroke
				(width 0.2032)
				(type default)
			)
			(layer "F.SilkS")
		)
		(fp_rect
			(start -0.5842 1.3335)
			(end 0.5842 -1.3335)
			(stroke
				(width 0)
				(type default)
			)
			(fill no)
			(layer "F.CrtYd")
		)
		(fp_rect
			(start -0.5842 1.3335)
			(end 0.5842 -1.3335)
			(stroke
				(width 0)
				(type default)
			)
			(fill no)
			(layer "F.Fab")
		)
		(pad "1" smd custom
			(at 0 -0.762 270)
			(size 0.2159 0.2159)
			(layers "F.Cu" "F.Mask" "F.Paste")
			(net "P1V8_STBY_VBST_RR")
			(options
				(clearance outline)
				(anchor circle)
			)
			(primitives
				(gr_poly
					(pts
						(arc
							(start -0.3302 -0.4318)
							(mid -0.402042 -0.402042)
							(end -0.4318 -0.3302)
						)
						(arc
							(start -0.4318 0.3302)
							(mid -0.402042 0.402042)
							(end -0.3302 0.4318)
						)
						(arc
							(start 0.3302 0.4318)
							(mid 0.402042 0.402042)
							(end 0.4318 0.3302)
						)
						(arc
							(start 0.4318 -0.3302)
							(mid 0.402042 -0.402042)
							(end 0.3302 -0.4318)
						)
					)
					(width 0)
					(fill yes)
				)
			)
		)
		(pad "2" smd custom
			(at 0 0.762 270)
			(size 0.2159 0.2159)
			(layers "F.Cu" "F.Mask" "F.Paste")
			(net "P1V8_STBY_SW")
			(options
				(clearance outline)
				(anchor circle)
			)
			(primitives
				(gr_poly
					(pts
						(arc
							(start -0.3302 -0.4318)
							(mid -0.402042 -0.402042)
							(end -0.4318 -0.3302)
						)
						(arc
							(start -0.4318 0.3302)
							(mid -0.402042 0.402042)
							(end -0.3302 0.4318)
						)
						(arc
							(start 0.3302 0.4318)
							(mid 0.402042 0.402042)
							(end 0.4318 0.3302)
						)
						(arc
							(start 0.4318 -0.3302)
							(mid 0.402042 -0.402042)
							(end 0.3302 -0.4318)
						)
					)
					(width 0)
					(fill yes)
				)
			)
		)
	)
	(footprint ""
		(layer "F.Cu")
		(at 41.8592 -161.3662)
		(property "Reference" "R309"
			(at 0 0 0)
			(layer "F.SilkS")
			(hide yes)
			(effects
				(font
					(size 1.27 1.27)
				)
			)
		)
		(property "Value" "4K7R2F-GP"
			(at 0.064008 -3.993896 0)
			(unlocked yes)
			(layer "F.Fab")
			(hide yes)
			(effects
				(font
					(size 1.016 1.016)
					(thickness 0.1524)
				)
			)
		)
		(property "Device Type" "R402H16"
			(at 0.064008 -5.517896 0)
			(unlocked yes)
			(layer "F.Fab")
			(hide yes)
			(effects
				(font
					(size 1.016 1.016)
					(thickness 0.1524)
				)
			)
		)
		(duplicate_pad_numbers_are_jumpers no)
		(fp_line
			(start -0.508 -0.9398)
			(end -0.508 0.9398)
			(stroke
				(width 0.1524)
				(type default)
			)
			(layer "F.SilkS")
		)
		(fp_line
			(start 0.508 -0.9398)
			(end -0.508 -0.9398)
			(stroke
				(width 0.1524)
				(type default)
			)
			(layer "F.SilkS")
		)
		(fp_rect
			(start -0.508 0.9398)
			(end 0.508 -0.9398)
			(stroke
				(width 0)
				(type default)
			)
			(fill no)
			(layer "F.CrtYd")
		)
		(fp_rect
			(start -0.508 0.9398)
			(end 0.508 -0.9398)
			(stroke
				(width 0)
				(type default)
			)
			(fill no)
			(layer "F.Fab")
		)
		(pad "1" smd custom
			(at 0 -0.4445)
			(size 0.1397 0.1397)
			(layers "F.Cu" "F.Mask" "F.Paste")
			(net "P3V3_STBY")
			(options
				(clearance outline)
				(anchor circle)
			)
			(primitives
				(gr_poly
					(pts
						(arc
							(start -0.1778 -0.2794)
							(mid -0.249642 -0.249642)
							(end -0.2794 -0.1778)
						)
						(arc
							(start -0.2794 0.1778)
							(mid -0.249642 0.249642)
							(end -0.1778 0.2794)
						)
						(arc
							(start 0.1778 0.2794)
							(mid 0.249642 0.249642)
							(end 0.2794 0.1778)
						)
						(arc
							(start 0.2794 -0.1778)
							(mid 0.249642 -0.249642)
							(end 0.1778 -0.2794)
						)
					)
					(width 0)
					(fill yes)
				)
			)
		)
		(pad "2" smd custom
			(at 0 0.4445)
			(size 0.1397 0.1397)
			(layers "F.Cu" "F.Mask" "F.Paste")
			(net "BOARD_REV_0")
			(options
				(clearance outline)
				(anchor circle)
			)
			(primitives
				(gr_poly
					(pts
						(arc
							(start -0.1778 -0.2794)
							(mid -0.249642 -0.249642)
							(end -0.2794 -0.1778)
						)
						(arc
							(start -0.2794 0.1778)
							(mid -0.249642 0.249642)
							(end -0.1778 0.2794)
						)
						(arc
							(start 0.1778 0.2794)
							(mid 0.249642 0.249642)
							(end 0.2794 0.1778)
						)
						(arc
							(start 0.2794 -0.1778)
							(mid 0.249642 -0.249642)
							(end 0.1778 -0.2794)
						)
					)
					(width 0)
					(fill yes)
				)
			)
		)
	)
	(footprint ""
		(layer "F.Cu")
		(at 41.450006 -169.999914)
		(property "Reference" "NUT1"
			(at 0 0 0)
			(layer "F.SilkS")
			(hide yes)
			(effects
				(font
					(size 1.27 1.27)
				)
			)
		)
		(property "Value" "STF256R168H278-GP"
			(at -4.826 0.0508 0)
			(unlocked yes)
			(layer "F.Fab")
			(hide yes)
			(effects
				(font
					(size 1.016 1.016)
					(thickness 0.1524)
				)
			)
		)
		(property "Device Type" "STF256R168H278"
			(at -4.826 -1.4732 0)
			(unlocked yes)
			(layer "F.Fab")
			(hide yes)
			(effects
				(font
					(size 1.016 1.016)
					(thickness 0.1524)
				)
			)
		)
		(duplicate_pad_numbers_are_jumpers no)
		(fp_circle
			(center 0 0)
			(end 3.6068 0)
			(stroke
				(width 0.3048)
				(type default)
			)
			(fill no)
			(layer "F.SilkS")
		)
		(fp_poly
			(pts
				(arc
					(start 3.7592 0)
					(mid -3.7592 0)
					(end 3.7592 0)
				)
			)
			(stroke
				(width 0)
				(type default)
			)
			(fill no)
			(layer "B.CrtYd")
		)
		(fp_poly
			(pts
				(arc
					(start 2.5019 0)
					(mid -2.5019 0)
					(end 2.5019 0)
				)
			)
			(stroke
				(width 0)
				(type default)
			)
			(fill no)
			(layer "F.CrtYd")
		)
		(fp_poly
			(pts
				(arc
					(start 3.7592 0.00635)
					(mid -3.759205 0)
					(end 3.7592 -0.00635)
				)
				(arc
					(start 2.5019 -0.00635)
					(mid -2.501908 0)
					(end 2.5019 0.00635)
				)
			)
			(stroke
				(width 0)
				(type default)
			)
			(fill no)
			(layer "F.CrtYd")
		)
		(fp_poly
			(pts
				(arc
					(start 3.7592 0)
					(mid -3.7592 0)
					(end 3.7592 0)
				)
			)
			(stroke
				(width 0)
				(type default)
			)
			(fill no)
			(layer "B.Fab")
		)
		(fp_poly
			(pts
				(arc
					(start 3.7592 0)
					(mid -3.7592 0)
					(end 3.7592 0)
				)
			)
			(stroke
				(width 0)
				(type default)
			)
			(fill no)
			(layer "F.Fab")
		)
		(pad "1" thru_hole circle
			(at 0 0)
			(size 6.5024 6.5024)
			(drill 4.2672)
			(layers "*.Cu" "*.Mask")
			(remove_unused_layers no)
			(net "Net_97")
			(clearance -0.6096)
			(thermal_gap 0.3048)
			(padstack
				(mode front_inner_back)
				(layer "Inner"
					(shape circle)
					(size 4.6736 4.6736)
					(clearance 0.3048)
				)
				(layer "B.Cu"
					(shape circle)
					(size 6.5024 6.5024)
					(clearance -0.6096)
				)
			)
		)
	)
)
